# T6G (Grand Teton) — schematic netlist excerpt (pin names and nets, part order shuffled) for the footprints in the layout excerpt that follows; sources: Cadence DE-HDL packaged netlist, KiCad conversion of 04192023_DAF0TMB3IC0_F0TG_MB_C_brd_V02_OCP.brd

R3296  Q_RES  4.7K 1% CHIP  pkg 0402LF  page 144 : A = P3V3_AUX ; B = HDD_ACTIVITY_BUF
PC6637_2  Q_CAP  22UF 16V 20% X6S  pkg C0805  page 365 : A = SW_P12V_AUX_P0V9_RETIMER_CPU1_FLT ; B = GND
R1503  Q_RES  30K 1% CHIP  pkg 0402LF  page 29 : A = PVDD18_S5_P0 ; B = ESPI_CPU0_D0

(kicad_pcb
	(version 20260206)
	(generator "pcbnew")
	(generator_version "10.0")
	(general
		(thickness 1.6)
		(legacy_teardrops no)
	)
	(paper "A4")
	(title_block
		(title "04192023_DAF0TMB3IC0_F0TG_MB_C_brd_V02_OCP.brd")
		(comment 1 "Grand Teton / footprints 782-784 of 8354")
	)
	(layers
		(0 "F.Cu" signal "TOP")
		(4 "In1.Cu" signal "GND")
		(6 "In2.Cu" signal "IN1")
		(8 "In3.Cu" signal "GND1")
		(10 "In4.Cu" signal "IN2")
		(12 "In5.Cu" signal "GND2")
		(14 "In6.Cu" signal "IN3")
		(16 "In7.Cu" signal "GND3")
		(18 "In8.Cu" signal "VCC")
		(20 "In9.Cu" signal "VCC1")
		(22 "In10.Cu" signal "GND4")
		(24 "In11.Cu" signal "IN4")
		(26 "In12.Cu" signal "GND5")
		(28 "In13.Cu" signal "IN5")
		(30 "In14.Cu" signal "GND6")
		(32 "In15.Cu" signal "IN6")
		(34 "In16.Cu" signal "GND7")
		(2 "B.Cu" signal "BOTTOM")
		(9 "F.Adhes" user "F.Adhesive")
		(11 "B.Adhes" user "B.Adhesive")
		(13 "F.Paste" user "Package Geometry/Pastemask Top")
		(15 "B.Paste" user "Package Geometry/Pastemask Bottom")
		(5 "F.SilkS" user "Ref Des/Silkscreen Top")
		(7 "B.SilkS" user "Ref Des/Silkscreen Bottom")
		(1 "F.Mask" user "Board Geometry/Soldermask Top")
		(3 "B.Mask" user "Board Geometry/Soldermask Bottom")
		(17 "Dwgs.User" user "User.Drawings")
		(19 "Cmts.User" user "User.Comments")
		(21 "Eco1.User" user "User.Eco1")
		(23 "Eco2.User" user "User.Eco2")
		(25 "Edge.Cuts" user "Board Geometry/Outline")
		(27 "Margin" user)
		(31 "F.CrtYd" user "Package Geometry/Place Bound Top")
		(29 "B.CrtYd" user "Package Geometry/Place Bound Bottom")
		(35 "F.Fab" user "Ref Des/Assembly Top")
		(33 "B.Fab" user "Ref Des/Assembly Bottom")
	)
	(footprint ""
		(layer "F.Cu")
		(at 395.751558 -323.796152 90)
		(property "Reference" "R1503"
			(at 0 0 90)
			(layer "F.SilkS")
			(hide yes)
			(effects
				(font
					(size 1.27 1.27)
				)
			)
		)
		(property "Value" ""
			(at 0 0 90)
			(layer "F.Fab")
			(effects
				(font
					(size 1.27 1.27)
				)
			)
		)
		(duplicate_pad_numbers_are_jumpers no)
		(fp_line
			(start 0.7874 -0.4064)
			(end 0.7874 0.4064)
			(stroke
				(width 0.1524)
				(type default)
			)
			(layer "F.SilkS")
		)
		(fp_line
			(start -0.7874 -0.4064)
			(end 0.7874 -0.4064)
			(stroke
				(width 0.1524)
				(type default)
			)
			(layer "F.SilkS")
		)
		(fp_line
			(start 0.7874 0.4064)
			(end -0.7874 0.4064)
			(stroke
				(width 0.1524)
				(type default)
			)
			(layer "F.SilkS")
		)
		(fp_line
			(start -0.7874 0.4064)
			(end -0.7874 -0.4064)
			(stroke
				(width 0.1524)
				(type default)
			)
			(layer "F.SilkS")
		)
		(fp_line
			(start -0.12065 -0.305054)
			(end -0.12065 -0.2794)
			(stroke
				(width 0.1)
				(type default)
			)
			(layer "F.Fab")
		)
		(fp_line
			(start -0.67945 -0.305054)
			(end -0.12065 -0.305054)
			(stroke
				(width 0.1)
				(type default)
			)
			(layer "F.Fab")
		)
		(fp_line
			(start 0.67945 -0.3048)
			(end 0.67945 0.3048)
			(stroke
				(width 0.1)
				(type default)
			)
			(layer "F.Fab")
		)
		(fp_line
			(start 0.12065 -0.3048)
			(end 0.67945 -0.3048)
			(stroke
				(width 0.1)
				(type default)
			)
			(layer "F.Fab")
		)
		(fp_line
			(start 0.12065 -0.2794)
			(end 0.12065 -0.3048)
			(stroke
				(width 0.1)
				(type default)
			)
			(layer "F.Fab")
		)
		(fp_line
			(start -0.12065 -0.2794)
			(end 0.12065 -0.2794)
			(stroke
				(width 0.1)
				(type default)
			)
			(layer "F.Fab")
		)
		(fp_line
			(start 0.120396 0.2794)
			(end -0.12065 0.2794)
			(stroke
				(width 0.1)
				(type default)
			)
			(layer "F.Fab")
		)
		(fp_line
			(start -0.12065 0.2794)
			(end -0.12065 0.3048)
			(stroke
				(width 0.1)
				(type default)
			)
			(layer "F.Fab")
		)
		(fp_line
			(start 0.67945 0.3048)
			(end 0.120396 0.3048)
			(stroke
				(width 0.1)
				(type default)
			)
			(layer "F.Fab")
		)
		(fp_line
			(start 0.120396 0.3048)
			(end 0.120396 0.2794)
			(stroke
				(width 0.1)
				(type default)
			)
			(layer "F.Fab")
		)
		(fp_line
			(start -0.12065 0.3048)
			(end -0.67945 0.3048)
			(stroke
				(width 0.1)
				(type default)
			)
			(layer "F.Fab")
		)
		(fp_line
			(start -0.67945 0.3048)
			(end -0.67945 -0.305054)
			(stroke
				(width 0.1)
				(type default)
			)
			(layer "F.Fab")
		)
		(pad "1" smd circle
			(at -0.40005 0 90)
			(size 0 0)
			(layers "F.Cu" "F.Mask" "F.Paste")
			(net "PVDD18_S5_P0")
		)
		(pad "2" smd circle
			(at 0.40005 0 90)
			(size 0 0)
			(layers "F.Cu" "F.Mask" "F.Paste")
			(net "ESPI_CPU0_D0")
		)
	)
	(footprint ""
		(layer "F.Cu")
		(at 30.936692 -397.396462)
		(property "Reference" "PC6637_2"
			(at 0 0 0)
			(layer "F.SilkS")
			(hide yes)
			(effects
				(font
					(size 1.27 1.27)
				)
			)
		)
		(property "Value" ""
			(at 0 0 0)
			(layer "F.Fab")
			(effects
				(font
					(size 1.27 1.27)
				)
			)
		)
		(duplicate_pad_numbers_are_jumpers no)
		(fp_line
			(start -1.524 -0.762)
			(end 1.524 -0.762)
			(stroke
				(width 0.1524)
				(type default)
			)
			(layer "F.SilkS")
		)
		(fp_line
			(start -1.524 0.762)
			(end -1.524 -0.762)
			(stroke
				(width 0.1524)
				(type default)
			)
			(layer "F.SilkS")
		)
		(fp_line
			(start 1.524 -0.762)
			(end 1.524 0.762)
			(stroke
				(width 0.1524)
				(type default)
			)
			(layer "F.SilkS")
		)
		(fp_line
			(start 1.524 0.762)
			(end -1.524 0.762)
			(stroke
				(width 0.1524)
				(type default)
			)
			(layer "F.SilkS")
		)
		(fp_line
			(start -1.1049 -0.724916)
			(end -1.1049 0.724916)
			(stroke
				(width 0.1)
				(type default)
			)
			(layer "F.Fab")
		)
		(fp_line
			(start -1.1049 0.724916)
			(end 1.1049 0.724916)
			(stroke
				(width 0.1)
				(type default)
			)
			(layer "F.Fab")
		)
		(fp_line
			(start 1.1049 -0.724916)
			(end -1.1049 -0.724916)
			(stroke
				(width 0.1)
				(type default)
			)
			(layer "F.Fab")
		)
		(fp_line
			(start 1.1049 0.724916)
			(end 1.1049 -0.724916)
			(stroke
				(width 0.1)
				(type default)
			)
			(layer "F.Fab")
		)
		(pad "1" smd rect
			(at -0.889 0 180)
			(size 1.016 1.27)
			(layers "F.Cu" "F.Mask" "F.Paste")
			(net "SW_P12V_AUX_P0V9_RETIMER_CPU1_FLT")
		)
		(pad "2" smd rect
			(at 0.889 0 180)
			(size 1.016 1.27)
			(layers "F.Cu" "F.Mask" "F.Paste")
			(net "GND")
		)
	)
	(footprint ""
		(layer "F.Cu")
		(at 140.886942 -105.225596)
		(property "Reference" "R3296"
			(at 0 0 0)
			(layer "F.SilkS")
			(hide yes)
			(effects
				(font
					(size 1.27 1.27)
				)
			)
		)
		(property "Value" ""
			(at 0 0 0)
			(layer "F.Fab")
			(effects
				(font
					(size 1.27 1.27)
				)
			)
		)
		(duplicate_pad_numbers_are_jumpers no)
		(fp_line
			(start -0.7874 -0.4064)
			(end 0.7874 -0.4064)
			(stroke
				(width 0.1524)
				(type default)
			)
			(layer "F.SilkS")
		)
		(fp_line
			(start -0.7874 0.4064)
			(end -0.7874 -0.4064)
			(stroke
				(width 0.1524)
				(type default)
			)
			(layer "F.SilkS")
		)
		(fp_line
			(start 0.7874 -0.4064)
			(end 0.7874 0.4064)
			(stroke
				(width 0.1524)
				(type default)
			)
			(layer "F.SilkS")
		)
		(fp_line
			(start 0.7874 0.4064)
			(end -0.7874 0.4064)
			(stroke
				(width 0.1524)
				(type default)
			)
			(layer "F.SilkS")
		)
		(fp_line
			(start -0.67945 -0.305054)
			(end -0.12065 -0.305054)
			(stroke
				(width 0.1)
				(type default)
			)
			(layer "F.Fab")
		)
		(fp_line
			(start -0.67945 0.3048)
			(end -0.67945 -0.305054)
			(stroke
				(width 0.1)
				(type default)
			)
			(layer "F.Fab")
		)
		(fp_line
			(start -0.12065 -0.305054)
			(end -0.12065 -0.2794)
			(stroke
				(width 0.1)
				(type default)
			)
			(layer "F.Fab")
		)
		(fp_line
			(start -0.12065 -0.2794)
			(end 0.12065 -0.2794)
			(stroke
				(width 0.1)
				(type default)
			)
			(layer "F.Fab")
		)
		(fp_line
			(start -0.12065 0.2794)
			(end -0.12065 0.3048)
			(stroke
				(width 0.1)
				(type default)
			)
			(layer "F.Fab")
		)
		(fp_line
			(start -0.12065 0.3048)
			(end -0.67945 0.3048)
			(stroke
				(width 0.1)
				(type default)
			)
			(layer "F.Fab")
		)
		(fp_line
			(start 0.120396 0.2794)
			(end -0.12065 0.2794)
			(stroke
				(width 0.1)
				(type default)
			)
			(layer "F.Fab")
		)
		(fp_line
			(start 0.120396 0.3048)
			(end 0.120396 0.2794)
			(stroke
				(width 0.1)
				(type default)
			)
			(layer "F.Fab")
		)
		(fp_line
			(start 0.12065 -0.3048)
			(end 0.67945 -0.3048)
			(stroke
				(width 0.1)
				(type default)
			)
			(layer "F.Fab")
		)
		(fp_line
			(start 0.12065 -0.2794)
			(end 0.12065 -0.3048)
			(stroke
				(width 0.1)
				(type default)
			)
			(layer "F.Fab")
		)
		(fp_line
			(start 0.67945 -0.3048)
			(end 0.67945 0.3048)
			(stroke
				(width 0.1)
				(type default)
			)
			(layer "F.Fab")
		)
		(fp_line
			(start 0.67945 0.3048)
			(end 0.120396 0.3048)
			(stroke
				(width 0.1)
				(type default)
			)
			(layer "F.Fab")
		)
		(pad "1" smd circle
			(at -0.40005 0)
			(size 0 0)
			(layers "F.Cu" "F.Mask" "F.Paste")
			(net "P3V3_AUX")
		)
		(pad "2" smd circle
			(at 0.40005 0)
			(size 0 0)
			(layers "F.Cu" "F.Mask" "F.Paste")
			(net "HDD_ACTIVITY_BUF")
		)
	)
)
